# S9S_MB_2U (Grand Teton) — schematic netlist excerpt (pin names and nets, part order shuffled) for the footprints in the layout excerpt that follows; sources: Cadence DE-HDL packaged netlist, KiCad conversion of 03242023_DA0F0TMBIJ0_F0T_Motherboard_J_brd_V01_OCP.brd

PC278  Q_CAP  100NF 50V 10% X7R  pkg C0402  page 268 : A = SW_PVCCIN_CPU0_BOOT4_R ; B = SW_PVCCIN_CPU0_BOOTR4
C243  Q_CAP  10UF 6.3V 20% X6S  pkg C0402  page 77 : A = PVCCIN_CPU1 ; B = GND

(kicad_pcb
	(version 20260206)
	(generator "pcbnew")
	(generator_version "10.0")
	(general
		(thickness 1.6)
		(legacy_teardrops no)
	)
	(paper "A4")
	(title_block
		(title "03242023_DA0F0TMBIJ0_F0T_Motherboard_J_brd_V01_OCP.brd")
		(comment 1 "Grand Teton / footprints 4020-4021 of 6105")
	)
	(layers
		(0 "F.Cu" signal "TOP")
		(4 "In1.Cu" signal "GND")
		(6 "In2.Cu" signal "IN1")
		(8 "In3.Cu" signal "GND1")
		(10 "In4.Cu" signal "IN2")
		(12 "In5.Cu" signal "GND2")
		(14 "In6.Cu" signal "IN3")
		(16 "In7.Cu" signal "GND3")
		(18 "In8.Cu" signal "VCC")
		(20 "In9.Cu" signal "VCC1")
		(22 "In10.Cu" signal "GND4")
		(24 "In11.Cu" signal "IN4")
		(26 "In12.Cu" signal "GND5")
		(28 "In13.Cu" signal "IN5")
		(30 "In14.Cu" signal "GND6")
		(32 "In15.Cu" signal "IN6")
		(34 "In16.Cu" signal "GND7")
		(2 "B.Cu" signal "BOTTOM")
		(9 "F.Adhes" user "F.Adhesive")
		(11 "B.Adhes" user "B.Adhesive")
		(13 "F.Paste" user "Package Geometry/Pastemask Top")
		(15 "B.Paste" user "Package Geometry/Pastemask Bottom")
		(5 "F.SilkS" user "Ref Des/Silkscreen Top")
		(7 "B.SilkS" user "Ref Des/Silkscreen Bottom")
		(1 "F.Mask" user "Board Geometry/Soldermask Top")
		(3 "B.Mask" user "Board Geometry/Soldermask Bottom")
		(17 "Dwgs.User" user "User.Drawings")
		(19 "Cmts.User" user "User.Comments")
		(21 "Eco1.User" user "User.Eco1")
		(23 "Eco2.User" user "User.Eco2")
		(25 "Edge.Cuts" user "Board Geometry/Outline")
		(27 "Margin" user)
		(31 "F.CrtYd" user "Package Geometry/Place Bound Top")
		(29 "B.CrtYd" user "Package Geometry/Place Bound Bottom")
		(35 "F.Fab" user "Ref Des/Assembly Top")
		(33 "B.Fab" user "Ref Des/Assembly Bottom")
	)
	(footprint ""
		(layer "F.Cu")
		(at 371.204998 -338.17814 -90)
		(property "Reference" "PC278"
			(at 0 0 270)
			(layer "F.SilkS")
			(hide yes)
			(effects
				(font
					(size 1.27 1.27)
				)
			)
		)
		(property "Value" ""
			(at 0 0 270)
			(layer "F.Fab")
			(effects
				(font
					(size 1.27 1.27)
				)
			)
		)
		(duplicate_pad_numbers_are_jumpers no)
		(fp_line
			(start -0.7874 0.4064)
			(end -0.7874 -0.4064)
			(stroke
				(width 0.1524)
				(type default)
			)
			(layer "F.SilkS")
		)
		(fp_line
			(start 0.7874 0.4064)
			(end -0.7874 0.4064)
			(stroke
				(width 0.1524)
				(type default)
			)
			(layer "F.SilkS")
		)
		(fp_line
			(start -0.7874 -0.4064)
			(end 0.7874 -0.4064)
			(stroke
				(width 0.1524)
				(type default)
			)
			(layer "F.SilkS")
		)
		(fp_line
			(start 0.7874 -0.4064)
			(end 0.7874 0.4064)
			(stroke
				(width 0.1524)
				(type default)
			)
			(layer "F.SilkS")
		)
		(fp_line
			(start -0.67945 0.3048)
			(end -0.67945 -0.305054)
			(stroke
				(width 0.1)
				(type default)
			)
			(layer "F.Fab")
		)
		(fp_line
			(start -0.12065 0.3048)
			(end -0.67945 0.3048)
			(stroke
				(width 0.1)
				(type default)
			)
			(layer "F.Fab")
		)
		(fp_line
			(start 0.120396 0.3048)
			(end 0.120396 0.2794)
			(stroke
				(width 0.1)
				(type default)
			)
			(layer "F.Fab")
		)
		(fp_line
			(start 0.67945 0.3048)
			(end 0.120396 0.3048)
			(stroke
				(width 0.1)
				(type default)
			)
			(layer "F.Fab")
		)
		(fp_line
			(start -0.12065 0.2794)
			(end -0.12065 0.3048)
			(stroke
				(width 0.1)
				(type default)
			)
			(layer "F.Fab")
		)
		(fp_line
			(start 0.120396 0.2794)
			(end -0.12065 0.2794)
			(stroke
				(width 0.1)
				(type default)
			)
			(layer "F.Fab")
		)
		(fp_line
			(start -0.12065 -0.2794)
			(end 0.12065 -0.2794)
			(stroke
				(width 0.1)
				(type default)
			)
			(layer "F.Fab")
		)
		(fp_line
			(start 0.12065 -0.2794)
			(end 0.12065 -0.3048)
			(stroke
				(width 0.1)
				(type default)
			)
			(layer "F.Fab")
		)
		(fp_line
			(start 0.12065 -0.3048)
			(end 0.67945 -0.3048)
			(stroke
				(width 0.1)
				(type default)
			)
			(layer "F.Fab")
		)
		(fp_line
			(start 0.67945 -0.3048)
			(end 0.67945 0.3048)
			(stroke
				(width 0.1)
				(type default)
			)
			(layer "F.Fab")
		)
		(fp_line
			(start -0.67945 -0.305054)
			(end -0.12065 -0.305054)
			(stroke
				(width 0.1)
				(type default)
			)
			(layer "F.Fab")
		)
		(fp_line
			(start -0.12065 -0.305054)
			(end -0.12065 -0.2794)
			(stroke
				(width 0.1)
				(type default)
			)
			(layer "F.Fab")
		)
		(pad "1" smd circle
			(at -0.40005 0 270)
			(size 0 0)
			(layers "F.Cu" "F.Mask" "F.Paste")
			(net "SW_PVCCIN_CPU0_BOOT4_R")
		)
		(pad "2" smd circle
			(at 0.40005 0 270)
			(size 0 0)
			(layers "F.Cu" "F.Mask" "F.Paste")
			(net "SW_PVCCIN_CPU0_BOOTR4")
		)
	)
	(footprint ""
		(layer "F.Cu")
		(at 118.542816 -252.956568 -90)
		(property "Reference" "C243"
			(at 0 0 270)
			(layer "F.SilkS")
			(hide yes)
			(effects
				(font
					(size 1.27 1.27)
				)
			)
		)
		(property "Value" ""
			(at 0 0 270)
			(layer "F.Fab")
			(effects
				(font
					(size 1.27 1.27)
				)
			)
		)
		(duplicate_pad_numbers_are_jumpers no)
		(fp_line
			(start -0.7874 0.4064)
			(end -0.7874 -0.4064)
			(stroke
				(width 0.1524)
				(type default)
			)
			(layer "F.SilkS")
		)
		(fp_line
			(start 0.7874 0.4064)
			(end -0.7874 0.4064)
			(stroke
				(width 0.1524)
				(type default)
			)
			(layer "F.SilkS")
		)
		(fp_line
			(start -0.7874 -0.4064)
			(end 0.7874 -0.4064)
			(stroke
				(width 0.1524)
				(type default)
			)
			(layer "F.SilkS")
		)
		(fp_line
			(start 0.7874 -0.4064)
			(end 0.7874 0.4064)
			(stroke
				(width 0.1524)
				(type default)
			)
			(layer "F.SilkS")
		)
		(fp_line
			(start -0.67945 0.3048)
			(end -0.67945 -0.305054)
			(stroke
				(width 0.1)
				(type default)
			)
			(layer "F.Fab")
		)
		(fp_line
			(start -0.12065 0.3048)
			(end -0.67945 0.3048)
			(stroke
				(width 0.1)
				(type default)
			)
			(layer "F.Fab")
		)
		(fp_line
			(start 0.120396 0.3048)
			(end 0.120396 0.2794)
			(stroke
				(width 0.1)
				(type default)
			)
			(layer "F.Fab")
		)
		(fp_line
			(start 0.67945 0.3048)
			(end 0.120396 0.3048)
			(stroke
				(width 0.1)
				(type default)
			)
			(layer "F.Fab")
		)
		(fp_line
			(start -0.12065 0.2794)
			(end -0.12065 0.3048)
			(stroke
				(width 0.1)
				(type default)
			)
			(layer "F.Fab")
		)
		(fp_line
			(start 0.120396 0.2794)
			(end -0.12065 0.2794)
			(stroke
				(width 0.1)
				(type default)
			)
			(layer "F.Fab")
		)
		(fp_line
			(start -0.12065 -0.2794)
			(end 0.12065 -0.2794)
			(stroke
				(width 0.1)
				(type default)
			)
			(layer "F.Fab")
		)
		(fp_line
			(start 0.12065 -0.2794)
			(end 0.12065 -0.3048)
			(stroke
				(width 0.1)
				(type default)
			)
			(layer "F.Fab")
		)
		(fp_line
			(start 0.12065 -0.3048)
			(end 0.67945 -0.3048)
			(stroke
				(width 0.1)
				(type default)
			)
			(layer "F.Fab")
		)
		(fp_line
			(start 0.67945 -0.3048)
			(end 0.67945 0.3048)
			(stroke
				(width 0.1)
				(type default)
			)
			(layer "F.Fab")
		)
		(fp_line
			(start -0.67945 -0.305054)
			(end -0.12065 -0.305054)
			(stroke
				(width 0.1)
				(type default)
			)
			(layer "F.Fab")
		)
		(fp_line
			(start -0.12065 -0.305054)
			(end -0.12065 -0.2794)
			(stroke
				(width 0.1)
				(type default)
			)
			(layer "F.Fab")
		)
		(pad "1" smd circle
			(at -0.40005 0 270)
			(size 0 0)
			(layers "F.Cu" "F.Mask" "F.Paste")
			(net "PVCCIN_CPU1")
		)
		(pad "2" smd circle
			(at 0.40005 0 270)
			(size 0 0)
			(layers "F.Cu" "F.Mask" "F.Paste")
			(net "GND")
		)
	)
)
